(kicad_pcb
	(version 20260206)
	(generator "pcbnew")
	(generator_version "10.0")
	(general
		(thickness 1.6)
		(legacy_teardrops no)
	)
	(paper "A4")
	(title_block
		(title "01162023_DA0F0TEBIF0_F0T_Expander_BD_F_brd_V02_OCP.brd")
		(comment 1 "Grand Teton / footprint 3770 of 9728 (J25), pads 110-179 of 179")
	)
	(layers
		(0 "F.Cu" signal "TOP")
		(4 "In1.Cu" signal "GND")
		(6 "In2.Cu" signal "VCC")
		(8 "In3.Cu" signal "VCC1")
		(10 "In4.Cu" signal "GND1")
		(12 "In5.Cu" signal "IN1")
		(14 "In6.Cu" signal "GND2")
		(16 "In7.Cu" signal "IN2")
		(18 "In8.Cu" signal "GND3")
		(20 "In9.Cu" signal "IN3")
		(22 "In10.Cu" signal "GND4")
		(24 "In11.Cu" signal "IN4")
		(26 "In12.Cu" signal "GND5")
		(28 "In13.Cu" signal "IN5")
		(30 "In14.Cu" signal "GND6")
		(32 "In15.Cu" signal "IN6")
		(34 "In16.Cu" signal "GND7")
		(2 "B.Cu" signal "BOTTOM")
		(9 "F.Adhes" user "F.Adhesive")
		(11 "B.Adhes" user "B.Adhesive")
		(13 "F.Paste" user "Package Geometry/Pastemask Top")
		(15 "B.Paste" user "Package Geometry/Pastemask Bottom")
		(5 "F.SilkS" user "Ref Des/Silkscreen Top")
		(7 "B.SilkS" user "Ref Des/Silkscreen Bottom")
		(1 "F.Mask" user "Board Geometry/Soldermask Top")
		(3 "B.Mask" user "Board Geometry/Soldermask Bottom")
		(17 "Dwgs.User" user "User.Drawings")
		(19 "Cmts.User" user "User.Comments")
		(21 "Eco1.User" user "User.Eco1")
		(23 "Eco2.User" user "User.Eco2")
		(25 "Edge.Cuts" user "Board Geometry/Outline")
		(27 "Margin" user)
		(31 "F.CrtYd" user "Package Geometry/Place Bound Top")
		(29 "B.CrtYd" user "Package Geometry/Place Bound Bottom")
		(35 "F.Fab" user "Ref Des/Assembly Top")
		(33 "B.Fab" user "Ref Des/Assembly Bottom")
	)
	(footprint ""
		(layer "F.Cu")
		(at 304.179986 -127.700024 180)
		(property "Reference" "J25"
			(at 5.322316 -34.482024 90)
			(unlocked yes)
			(layer "F.SilkS")
			(effects
				(font
					(size 0.7874 0.5842)
					(thickness 0.1524)
				)
				(justify left)
			)
		)
		(property "Value" ""
			(at 0 0 180)
			(layer "F.Fab")
			(effects
				(font
					(size 1.27 1.27)
				)
			)
		)
		(duplicate_pad_numbers_are_jumpers no)
		(pad "B38" smd rect
			(at -1.27762 7.14502 90)
			(size 0.3556 1.2192)
			(layers "F.Cu" "F.Mask" "F.Paste")
			(net "GND")
		)
		(pad "B39" smd rect
			(at -1.27762 7.744968 90)
			(size 0.3556 1.2192)
			(layers "F.Cu" "F.Mask" "F.Paste")
			(net "P5E_PEX2_STN0_TX_C_DN<7>")
		)
		(pad "B40" smd rect
			(at -1.27762 8.344916 90)
			(size 0.3556 1.2192)
			(layers "F.Cu" "F.Mask" "F.Paste")
			(net "P5E_PEX2_STN0_TX_C_DP<7>")
		)
		(pad "B41" smd rect
			(at -1.27762 8.945118 90)
			(size 0.3556 1.2192)
			(layers "F.Cu" "F.Mask" "F.Paste")
			(net "GND")
		)
		(pad "B42" smd rect
			(at -1.27762 9.545066 90)
			(size 0.3556 1.2192)
			(layers "F.Cu" "F.Mask" "F.Paste")
			(net "PRSNTB0_NIC5_N")
		)
		(pad "B43" smd rect
			(at -1.27762 14.454886 90)
			(size 0.3556 1.2192)
			(layers "F.Cu" "F.Mask" "F.Paste")
			(net "GND")
		)
		(pad "B44" smd rect
			(at -1.27762 15.055088 90)
			(size 0.3556 1.2192)
			(layers "F.Cu" "F.Mask" "F.Paste")
			(net "P5E_PEX2_STN0_TX_C_DN<8>")
		)
		(pad "B45" smd rect
			(at -1.27762 15.655036 90)
			(size 0.3556 1.2192)
			(layers "F.Cu" "F.Mask" "F.Paste")
			(net "P5E_PEX2_STN0_TX_C_DP<8>")
		)
		(pad "B46" smd rect
			(at -1.27762 16.254984 90)
			(size 0.3556 1.2192)
			(layers "F.Cu" "F.Mask" "F.Paste")
			(net "GND")
		)
		(pad "B47" smd rect
			(at -1.27762 16.854932 90)
			(size 0.3556 1.2192)
			(layers "F.Cu" "F.Mask" "F.Paste")
			(net "P5E_PEX2_STN0_TX_C_DN<9>")
		)
		(pad "B48" smd rect
			(at -1.27762 17.45488 90)
			(size 0.3556 1.2192)
			(layers "F.Cu" "F.Mask" "F.Paste")
			(net "P5E_PEX2_STN0_TX_C_DP<9>")
		)
		(pad "B49" smd rect
			(at -1.27762 18.055082 90)
			(size 0.3556 1.2192)
			(layers "F.Cu" "F.Mask" "F.Paste")
			(net "GND")
		)
		(pad "B50" smd rect
			(at -1.27762 18.65503 90)
			(size 0.3556 1.2192)
			(layers "F.Cu" "F.Mask" "F.Paste")
			(net "P5E_PEX2_STN0_TX_C_DN<10>")
		)
		(pad "B51" smd rect
			(at -1.27762 19.254978 90)
			(size 0.3556 1.2192)
			(layers "F.Cu" "F.Mask" "F.Paste")
			(net "P5E_PEX2_STN0_TX_C_DP<10>")
		)
		(pad "B52" smd rect
			(at -1.27762 19.854926 90)
			(size 0.3556 1.2192)
			(layers "F.Cu" "F.Mask" "F.Paste")
			(net "GND")
		)
		(pad "B53" smd rect
			(at -1.27762 20.455128 90)
			(size 0.3556 1.2192)
			(layers "F.Cu" "F.Mask" "F.Paste")
			(net "P5E_PEX2_STN0_TX_C_DN<11>")
		)
		(pad "B54" smd rect
			(at -1.27762 21.055076 90)
			(size 0.3556 1.2192)
			(layers "F.Cu" "F.Mask" "F.Paste")
			(net "P5E_PEX2_STN0_TX_C_DP<11>")
		)
		(pad "B55" smd rect
			(at -1.27762 21.655024 90)
			(size 0.3556 1.2192)
			(layers "F.Cu" "F.Mask" "F.Paste")
			(net "GND")
		)
		(pad "B56" smd rect
			(at -1.27762 22.254972 90)
			(size 0.3556 1.2192)
			(layers "F.Cu" "F.Mask" "F.Paste")
			(net "P5E_PEX2_STN0_TX_C_DP<12>")
		)
		(pad "B57" smd rect
			(at -1.27762 22.85492 90)
			(size 0.3556 1.2192)
			(layers "F.Cu" "F.Mask" "F.Paste")
			(net "P5E_PEX2_STN0_TX_C_DN<12>")
		)
		(pad "B58" smd rect
			(at -1.27762 23.455122 90)
			(size 0.3556 1.2192)
			(layers "F.Cu" "F.Mask" "F.Paste")
			(net "GND")
		)
		(pad "B59" smd rect
			(at -1.27762 24.05507 90)
			(size 0.3556 1.2192)
			(layers "F.Cu" "F.Mask" "F.Paste")
			(net "P5E_PEX2_STN0_TX_C_DN<13>")
		)
		(pad "B60" smd rect
			(at -1.27762 24.655018 90)
			(size 0.3556 1.2192)
			(layers "F.Cu" "F.Mask" "F.Paste")
			(net "P5E_PEX2_STN0_TX_C_DP<13>")
		)
		(pad "B61" smd rect
			(at -1.27762 25.254966 90)
			(size 0.3556 1.2192)
			(layers "F.Cu" "F.Mask" "F.Paste")
			(net "GND")
		)
		(pad "B62" smd rect
			(at -1.27762 25.854914 90)
			(size 0.3556 1.2192)
			(layers "F.Cu" "F.Mask" "F.Paste")
			(net "P5E_PEX2_STN0_TX_C_DP<14>")
		)
		(pad "B63" smd rect
			(at -1.27762 26.455116 90)
			(size 0.3556 1.2192)
			(layers "F.Cu" "F.Mask" "F.Paste")
			(net "P5E_PEX2_STN0_TX_C_DN<14>")
		)
		(pad "B64" smd rect
			(at -1.27762 27.055064 90)
			(size 0.3556 1.2192)
			(layers "F.Cu" "F.Mask" "F.Paste")
			(net "GND")
		)
		(pad "B65" smd rect
			(at -1.27762 27.655012 90)
			(size 0.3556 1.2192)
			(layers "F.Cu" "F.Mask" "F.Paste")
			(net "P5E_PEX2_STN0_TX_C_DN<15>")
		)
		(pad "B66" smd rect
			(at -1.27762 28.25496 90)
			(size 0.3556 1.2192)
			(layers "F.Cu" "F.Mask" "F.Paste")
			(net "P5E_PEX2_STN0_TX_C_DP<15>")
		)
		(pad "B67" smd rect
			(at -1.27762 28.854908 90)
			(size 0.3556 1.2192)
			(layers "F.Cu" "F.Mask" "F.Paste")
			(net "GND")
		)
		(pad "B68" smd rect
			(at -1.27762 29.45511 90)
			(size 0.3556 1.2192)
			(layers "F.Cu" "F.Mask" "F.Paste")
			(net "Net_2646")
		)
		(pad "B69" smd rect
			(at -1.27762 30.055058 90)
			(size 0.3556 1.2192)
			(layers "F.Cu" "F.Mask" "F.Paste")
			(net "Net_2647")
		)
		(pad "B70" smd rect
			(at -1.27762 30.655006 90)
			(size 0.3556 1.2192)
			(layers "F.Cu" "F.Mask" "F.Paste")
			(net "PRSNTB3_NIC5_N")
		)
		(pad "G1" thru_hole oval
			(at 1.022604 -34.034984 90)
			(size 1.6256 3.4798)
			(drill oval 1.1176 2.4638)
			(layers "*.Cu" "*.Mask")
			(remove_unused_layers no)
			(net "GND")
			(clearance 0.127)
			(thermal_gap 0.127)
		)
		(pad "G2" thru_hole oval
			(at 1.022604 -20.625054 90)
			(size 1.6256 3.4798)
			(drill oval 1.1176 2.4638)
			(layers "*.Cu" "*.Mask")
			(remove_unused_layers no)
			(net "GND")
			(clearance 0.127)
			(thermal_gap 0.127)
		)
		(pad "G3" thru_hole oval
			(at 1.022604 -0.255016 90)
			(size 1.6256 3.4798)
			(drill oval 1.1176 2.4638)
			(layers "*.Cu" "*.Mask")
			(remove_unused_layers no)
			(net "GND")
			(clearance 0.127)
			(thermal_gap 0.127)
		)
		(pad "G4" thru_hole oval
			(at 1.022604 12.005056 90)
			(size 1.6256 3.4798)
			(drill oval 1.1176 2.4638)
			(layers "*.Cu" "*.Mask")
			(remove_unused_layers no)
			(net "GND")
			(clearance 0.127)
			(thermal_gap 0.127)
		)
		(pad "G5" thru_hole oval
			(at 1.022604 34.034984 90)
			(size 1.5748 3.4798)
			(drill oval 1.1176 2.4638)
			(layers "*.Cu" "*.Mask")
			(remove_unused_layers no)
			(net "GND")
			(clearance 0.1524)
			(thermal_gap 0.1524)
		)
		(pad "G6" thru_hole circle
			(at -3.16738 -20.625054 180)
			(size 1.6256 1.6256)
			(drill 1.1176)
			(layers "*.Cu" "*.Mask")
			(remove_unused_layers no)
			(net "GND")
			(clearance 0)
		)
		(pad "G7" thru_hole circle
			(at -3.16738 12.005056 180)
			(size 1.6256 1.6256)
			(drill 1.1176)
			(layers "*.Cu" "*.Mask")
			(remove_unused_layers no)
			(net "GND")
			(clearance 0)
		)
		(pad "G8" thru_hole circle
			(at 4.20243 -20.625054 180)
			(size 1.6256 1.6256)
			(drill 1.1176)
			(layers "*.Cu" "*.Mask")
			(remove_unused_layers no)
			(net "GND")
			(clearance 0)
		)
		(pad "G9" thru_hole circle
			(at 4.20243 12.005056 180)
			(size 1.6256 1.6256)
			(drill 1.1176)
			(layers "*.Cu" "*.Mask")
			(remove_unused_layers no)
			(net "GND")
			(clearance 0)
		)
		(pad "OA1" smd rect
			(at 3.322574 -30.660086 90)
			(size 0.3556 1.2192)
			(layers "F.Cu" "F.Mask" "F.Paste")
			(net "RST_NIC5_PERST2_R_N")
		)
		(pad "OA2" smd rect
			(at 3.322574 -30.059884 90)
			(size 0.3556 1.2192)
			(layers "F.Cu" "F.Mask" "F.Paste")
			(net "RST_NIC5_PERST3_R_N")
		)
		(pad "OA3" smd rect
			(at 3.322574 -29.459936 90)
			(size 0.3556 1.2192)
			(layers "F.Cu" "F.Mask" "F.Paste")
			(net "Net_2650")
		)
		(pad "OA4" smd rect
			(at 3.322574 -28.859988 90)
			(size 0.3556 1.2192)
			(layers "F.Cu" "F.Mask" "F.Paste")
			(net "NIC5_RBT_ARB_IN")
		)
		(pad "OA5" smd rect
			(at 3.322574 -28.26004 90)
			(size 0.3556 1.2192)
			(layers "F.Cu" "F.Mask" "F.Paste")
			(net "NIC5_RBT_ARB_OUT")
		)
		(pad "OA6" smd rect
			(at 3.322574 -27.660092 90)
			(size 0.3556 1.2192)
			(layers "F.Cu" "F.Mask" "F.Paste")
			(net "NIC5_SLOT_ID1")
		)
		(pad "OA7" smd rect
			(at 3.322574 -27.05989 90)
			(size 0.3556 1.2192)
			(layers "F.Cu" "F.Mask" "F.Paste")
			(net "NCSI_NIC5_TX_EN")
		)
		(pad "OA8" smd rect
			(at 3.322574 -26.459942 90)
			(size 0.3556 1.2192)
			(layers "F.Cu" "F.Mask" "F.Paste")
			(net "NCSI_NIC5_TXD1")
		)
		(pad "OA9" smd rect
			(at 3.322574 -25.859994 90)
			(size 0.3556 1.2192)
			(layers "F.Cu" "F.Mask" "F.Paste")
			(net "NCSI_NIC5_TXD0")
		)
		(pad "OA10" smd rect
			(at 3.322574 -25.260046 90)
			(size 0.3556 1.2192)
			(layers "F.Cu" "F.Mask" "F.Paste")
			(net "GND")
		)
		(pad "OA11" smd rect
			(at 3.322574 -24.660098 90)
			(size 0.3556 1.2192)
			(layers "F.Cu" "F.Mask" "F.Paste")
			(net "Net_2642")
		)
		(pad "OA12" smd rect
			(at 3.322574 -24.059896 90)
			(size 0.3556 1.2192)
			(layers "F.Cu" "F.Mask" "F.Paste")
			(net "Net_2645")
		)
		(pad "OA13" smd rect
			(at 3.322574 -23.459948 90)
			(size 0.3556 1.2192)
			(layers "F.Cu" "F.Mask" "F.Paste")
			(net "GND")
		)
		(pad "OA14" smd rect
			(at 3.322574 -22.86 90)
			(size 0.3556 1.2192)
			(layers "F.Cu" "F.Mask" "F.Paste")
			(net "CLK_50M_NIC5_RBT_REF")
		)
		(pad "OB1" smd rect
			(at -1.27762 -30.660086 90)
			(size 0.3556 1.2192)
			(layers "F.Cu" "F.Mask" "F.Paste")
			(net "PWRGD_NIC5_PWR_GOOD")
		)
		(pad "OB2" smd rect
			(at -1.27762 -30.059884 90)
			(size 0.3556 1.2192)
			(layers "F.Cu" "F.Mask" "F.Paste")
			(net "NIC5_MAIN_PWR_EN_R")
		)
		(pad "OB3" smd rect
			(at -1.27762 -29.459936 90)
			(size 0.3556 1.2192)
			(layers "F.Cu" "F.Mask" "F.Paste")
			(net "NIC5_LD_N")
		)
		(pad "OB4" smd rect
			(at -1.27762 -28.859988 90)
			(size 0.3556 1.2192)
			(layers "F.Cu" "F.Mask" "F.Paste")
			(net "NIC5_DATA_IN")
		)
		(pad "OB5" smd rect
			(at -1.27762 -28.26004 90)
			(size 0.3556 1.2192)
			(layers "F.Cu" "F.Mask" "F.Paste")
			(net "NIC5_DATA_OUT")
		)
		(pad "OB6" smd rect
			(at -1.27762 -27.660092 90)
			(size 0.3556 1.2192)
			(layers "F.Cu" "F.Mask" "F.Paste")
			(net "NIC5_CLK")
		)
		(pad "OB7" smd rect
			(at -1.27762 -27.05989 90)
			(size 0.3556 1.2192)
			(layers "F.Cu" "F.Mask" "F.Paste")
			(net "NIC5_SLOT_ID0")
		)
		(pad "OB8" smd rect
			(at -1.27762 -26.459942 90)
			(size 0.3556 1.2192)
			(layers "F.Cu" "F.Mask" "F.Paste")
			(net "NCSI_NIC5_RXD1")
		)
		(pad "OB9" smd rect
			(at -1.27762 -25.859994 90)
			(size 0.3556 1.2192)
			(layers "F.Cu" "F.Mask" "F.Paste")
			(net "NCSI_NIC5_RXD0")
		)
		(pad "OB10" smd rect
			(at -1.27762 -25.260046 90)
			(size 0.3556 1.2192)
			(layers "F.Cu" "F.Mask" "F.Paste")
			(net "GND")
		)
		(pad "OB11" smd rect
			(at -1.27762 -24.660098 90)
			(size 0.3556 1.2192)
			(layers "F.Cu" "F.Mask" "F.Paste")
			(net "Net_2641")
		)
		(pad "OB12" smd rect
			(at -1.27762 -24.059896 90)
			(size 0.3556 1.2192)
			(layers "F.Cu" "F.Mask" "F.Paste")
			(net "Net_2644")
		)
		(pad "OB13" smd rect
			(at -1.27762 -23.459948 90)
			(size 0.3556 1.2192)
			(layers "F.Cu" "F.Mask" "F.Paste")
			(net "GND")
		)
		(pad "OB14" smd rect
			(at -1.27762 -22.86 90)
			(size 0.3556 1.2192)
			(layers "F.Cu" "F.Mask" "F.Paste")
			(net "NCSI_NIC5_CRS_DV")
		)
	)
)
